#ISCELL
  mstr_misc dns *
  *
#ISCELL
  mstr_symbols design_note *
  *
#ISCELL
  mstr_symbols intel_corp_bpage *
  *
#CELL
  mstr_clock nb3w1200l *
  page102_i1
#CELL
  mstr_discrete cap *
  page102_i10
#CELL
  mstr_discrete fet_n_dual *
  page102_i101
#CELL
  mstr_discrete fet_n_dual *
  page102_i102
#CELL
  mstr_discrete res *
  page102_i103
#ISCELL
  mstr_symbols vcc_core *
  page102_i104
#CELL
  mstr_discrete res *
  page102_i105
#CELL
  mstr_discrete res *
  page102_i106
#ISCELL
  mstr_symbols vcc_core *
  page102_i107
#CELL
  mstr_discrete res *
  page102_i109
#CELL
  dev_discrete cap_a *
  page102_i11
#ISCELL
  mstr_symbols vcc_core *
  page102_i110
#ISCELL
  mstr_standard offpage *
  page102_i111
#CELL
  mstr_discrete fet_n *
  page102_i112
#ISCELL
  mstr_symbols gnd *
  page102_i113
#CELL
  mstr_discrete res *
  page102_i114
#CELL
  mstr_discrete res *
  page102_i115
#CELL
  dev_discrete cap_a *
  page102_i12
#CELL
  dev_discrete cap_a *
  page102_i13
#CELL
  dev_discrete cap_a *
  page102_i14
#CELL
  dev_discrete cap_a *
  page102_i15
#CELL
  dev_discrete cap_a *
  page102_i16
#ISCELL
  mstr_symbols gnd *
  page102_i17
#CELL
  dev_discrete cap_a *
  page102_i18
#CELL
  dev_discrete cap_a *
  page102_i19
#CELL
  mstr_discrete res *
  page102_i21
#ISCELL
  mstr_symbols gnd *
  page102_i22
#ISCELL
  mstr_symbols vcc_core *
  page102_i23
#ISCELL
  mstr_symbols vcc_core *
  page102_i24
#ISCELL
  mstr_symbols vcc_core *
  page102_i25
#CELL
  mstr_discrete res *
  page102_i26
#ISCELL
  mstr_symbols vcc_core *
  page102_i27
#CELL
  dev_discrete cap_a *
  page102_i28
#ISCELL
  mstr_symbols gnd *
  page102_i29
#CELL
  dev_discrete cap_a *
  page102_i30
#ISCELL
  mstr_standard offpage *
  page102_i31
#ISCELL
  mstr_standard offpage *
  page102_i32
#ISCELL
  mstr_standard offpage *
  page102_i33
#ISCELL
  mstr_standard offpage *
  page102_i34
#ISCELL
  mstr_standard offpage *
  page102_i35
#ISCELL
  mstr_standard offpage *
  page102_i36
#CELL
  mstr_discrete res *
  page102_i37
#CELL
  mstr_discrete res *
  page102_i38
#ISCELL
  mstr_standard offpage *
  page102_i4
#ISCELL
  mstr_standard offpage *
  page102_i41
#ISCELL
  mstr_standard offpage *
  page102_i42
#ISCELL
  mstr_symbols vcc_core *
  page102_i43
#ISCELL
  mstr_symbols gnd *
  page102_i44
#CELL
  mstr_discrete res *
  page102_i45
#CELL
  mstr_discrete res *
  page102_i46
#CELL
  mstr_discrete res *
  page102_i47
#ISCELL
  mstr_symbols vcc_core *
  page102_i49
#ISCELL
  mstr_standard offpage *
  page102_i5
#ISCELL
  mstr_symbols gnd *
  page102_i50
#ISCELL
  mstr_standard offpage *
  page102_i51
#ISCELL
  mstr_standard offpage *
  page102_i52
#CELL
  mstr_discrete res *
  page102_i53
#ISCELL
  mstr_standard offpage *
  page102_i54
#ISCELL
  mstr_standard offpage *
  page102_i55
#ISCELL
  mstr_standard offpage *
  page102_i56
#ISCELL
  mstr_standard offpage *
  page102_i57
#ISCELL
  mstr_standard offpage *
  page102_i58
#ISCELL
  mstr_standard offpage *
  page102_i59
#ISCELL
  mstr_symbols gnd *
  page102_i6
#ISCELL
  mstr_standard offpage *
  page102_i60
#ISCELL
  mstr_standard offpage *
  page102_i61
#ISCELL
  mstr_standard offpage *
  page102_i62
#ISCELL
  mstr_standard offpage *
  page102_i63
#ISCELL
  mstr_standard offpage *
  page102_i64
#ISCELL
  mstr_standard offpage *
  page102_i65
#ISCELL
  mstr_standard offpage *
  page102_i66
#ISCELL
  mstr_standard offpage *
  page102_i67
#ISCELL
  mstr_standard offpage *
  page102_i68
#ISCELL
  mstr_standard offpage *
  page102_i69
#ISCELL
  mstr_standard offpage *
  page102_i70
#ISCELL
  mstr_standard offpage *
  page102_i71
#ISCELL
  mstr_standard offpage *
  page102_i72
#ISCELL
  mstr_standard offpage *
  page102_i73
#ISCELL
  mstr_standard offpage *
  page102_i74
#ISCELL
  mstr_standard offpage *
  page102_i75
#ISCELL
  mstr_standard offpage *
  page102_i76
#ISCELL
  mstr_standard offpage *
  page102_i77
#CELL
  dev_discrete cap_a *
  page102_i79
#CELL
  mstr_discrete ferrite *
  page102_i8
#CELL
  mstr_discrete res *
  page102_i80
#CELL
  mstr_discrete res *
  page102_i81
#ISCELL
  mstr_standard offpage *
  page102_i83
#ISCELL
  mstr_standard offpage *
  page102_i84
#ISCELL
  mstr_standard offpage *
  page102_i85
#ISCELL
  mstr_standard offpage *
  page102_i86
#ISCELL
  mstr_standard offpage *
  page102_i89
#ISCELL
  mstr_symbols p3v3 *
  page102_i9
#ISCELL
  mstr_standard offpage *
  page102_i90
#CELL
  mstr_discrete res *
  page102_i93
#CELL
  mstr_discrete res *
  page102_i94
#ISCELL
  mstr_symbols p3v3 *
  page102_i95
#ISCELL
  mstr_standard offpage *
  page102_i96
#ISCELL
  mstr_standard offpage *
  page102_i97
#ISCELL
  mstr_standard offpage *
  page102_i98
#ISCELL
  mstr_standard offpage *
  page102_i99
